# T6G (Grand Teton) — schematic netlist excerpt (pin names and nets, part order shuffled) for the footprints in the layout excerpt that follows; sources: Cadence DE-HDL packaged netlist, KiCad conversion of 04192023_DAF0TMB3IC0_F0TG_MB_C_brd_V02_OCP.brd

C535  Q_CAP  10UF 25V 10% X6S  pkg C0805  page 106 : A = P12V_MEM_CPU1 ; B = GND
R536  Q_RES  2.2K 5% EMPTY  pkg 0402LF  page 54 : A = CPU1_THERMTRIP_N ; B = PVDD18_S5_P1
C1035  Q_CAP  0.1UF 10V 10% X7S  pkg C0201  page 312 : A = P0V9_CPU0_RT3_2A ; B = GND

(kicad_pcb
	(version 20260206)
	(generator "pcbnew")
	(generator_version "10.0")
	(general
		(thickness 1.6)
		(legacy_teardrops no)
	)
	(paper "A4")
	(title_block
		(title "04192023_DAF0TMB3IC0_F0TG_MB_C_brd_V02_OCP.brd")
		(comment 1 "Grand Teton / footprints 8265-8267 of 8354")
	)
	(layers
		(0 "F.Cu" signal "TOP")
		(4 "In1.Cu" signal "GND")
		(6 "In2.Cu" signal "IN1")
		(8 "In3.Cu" signal "GND1")
		(10 "In4.Cu" signal "IN2")
		(12 "In5.Cu" signal "GND2")
		(14 "In6.Cu" signal "IN3")
		(16 "In7.Cu" signal "GND3")
		(18 "In8.Cu" signal "VCC")
		(20 "In9.Cu" signal "VCC1")
		(22 "In10.Cu" signal "GND4")
		(24 "In11.Cu" signal "IN4")
		(26 "In12.Cu" signal "GND5")
		(28 "In13.Cu" signal "IN5")
		(30 "In14.Cu" signal "GND6")
		(32 "In15.Cu" signal "IN6")
		(34 "In16.Cu" signal "GND7")
		(2 "B.Cu" signal "BOTTOM")
		(9 "F.Adhes" user "F.Adhesive")
		(11 "B.Adhes" user "B.Adhesive")
		(13 "F.Paste" user "Package Geometry/Pastemask Top")
		(15 "B.Paste" user "Package Geometry/Pastemask Bottom")
		(5 "F.SilkS" user "Ref Des/Silkscreen Top")
		(7 "B.SilkS" user "Ref Des/Silkscreen Bottom")
		(1 "F.Mask" user "Board Geometry/Soldermask Top")
		(3 "B.Mask" user "Board Geometry/Soldermask Bottom")
		(17 "Dwgs.User" user "User.Drawings")
		(19 "Cmts.User" user "User.Comments")
		(21 "Eco1.User" user "User.Eco1")
		(23 "Eco2.User" user "User.Eco2")
		(25 "Edge.Cuts" user "Board Geometry/Outline")
		(27 "Margin" user)
		(31 "F.CrtYd" user "Package Geometry/Place Bound Top")
		(29 "B.CrtYd" user "Package Geometry/Place Bound Bottom")
		(35 "F.Fab" user "Ref Des/Assembly Top")
		(33 "B.Fab" user "Ref Des/Assembly Bottom")
	)
	(footprint ""
		(layer "B.Cu")
		(at 183.616346 -192.66027)
		(property "Reference" "C535"
			(at 0 0 0)
			(layer "B.SilkS")
			(hide yes)
			(effects
				(font
					(size 1.27 1.27)
				)
				(justify mirror)
			)
		)
		(property "Value" ""
			(at 0 0 0)
			(layer "B.Fab")
			(effects
				(font
					(size 1.27 1.27)
				)
				(justify mirror)
			)
		)
		(duplicate_pad_numbers_are_jumpers no)
		(fp_line
			(start -1.524 -0.762)
			(end -1.524 0.762)
			(stroke
				(width 0.1524)
				(type default)
			)
			(layer "B.SilkS")
		)
		(fp_line
			(start -1.524 0.762)
			(end 1.524 0.762)
			(stroke
				(width 0.1524)
				(type default)
			)
			(layer "B.SilkS")
		)
		(fp_line
			(start 1.524 -0.762)
			(end -1.524 -0.762)
			(stroke
				(width 0.1524)
				(type default)
			)
			(layer "B.SilkS")
		)
		(fp_line
			(start 1.524 0.762)
			(end 1.524 -0.762)
			(stroke
				(width 0.1524)
				(type default)
			)
			(layer "B.SilkS")
		)
		(fp_line
			(start -1.1049 -0.724916)
			(end 1.1049 -0.724916)
			(stroke
				(width 0.1)
				(type default)
			)
			(layer "B.Fab")
		)
		(fp_line
			(start -1.1049 0.724916)
			(end -1.1049 -0.724916)
			(stroke
				(width 0.1)
				(type default)
			)
			(layer "B.Fab")
		)
		(fp_line
			(start 1.1049 -0.724916)
			(end 1.1049 0.724916)
			(stroke
				(width 0.1)
				(type default)
			)
			(layer "B.Fab")
		)
		(fp_line
			(start 1.1049 0.724916)
			(end -1.1049 0.724916)
			(stroke
				(width 0.1)
				(type default)
			)
			(layer "B.Fab")
		)
		(pad "1" smd rect
			(at 0.889 0)
			(size 1.016 1.27)
			(layers "B.Cu" "B.Mask" "B.Paste")
			(net "P12V_MEM_CPU1")
		)
		(pad "2" smd rect
			(at -0.889 0)
			(size 1.016 1.27)
			(layers "B.Cu" "B.Mask" "B.Paste")
			(net "GND")
		)
	)
	(footprint ""
		(layer "B.Cu")
		(at 374.218454 -396.393162 -90)
		(property "Reference" "C1035"
			(at 0 0 90)
			(layer "B.SilkS")
			(hide yes)
			(effects
				(font
					(size 1.27 1.27)
				)
				(justify mirror)
			)
		)
		(property "Value" ""
			(at 0 0 90)
			(layer "B.Fab")
			(effects
				(font
					(size 1.27 1.27)
				)
				(justify mirror)
			)
		)
		(duplicate_pad_numbers_are_jumpers no)
		(fp_line
			(start -0.299974 0.150114)
			(end 0.299974 0.150114)
			(stroke
				(width 0.1)
				(type default)
			)
			(layer "B.Fab")
		)
		(fp_line
			(start 0.299974 0.150114)
			(end 0.299974 -0.150114)
			(stroke
				(width 0.1)
				(type default)
			)
			(layer "B.Fab")
		)
		(fp_line
			(start -0.299974 -0.150114)
			(end -0.299974 0.150114)
			(stroke
				(width 0.1)
				(type default)
			)
			(layer "B.Fab")
		)
		(fp_line
			(start 0.299974 -0.150114)
			(end -0.299974 -0.150114)
			(stroke
				(width 0.1)
				(type default)
			)
			(layer "B.Fab")
		)
		(pad "1" smd rect
			(at 0.2667 0 90)
			(size 0.3048 0.381)
			(layers "B.Cu" "B.Mask" "B.Paste")
			(net "P0V9_CPU0_RT3_2A")
		)
		(pad "2" smd rect
			(at -0.2667 0 90)
			(size 0.3048 0.381)
			(layers "B.Cu" "B.Mask" "B.Paste")
			(net "GND")
		)
	)
	(footprint ""
		(layer "B.Cu")
		(at 144.922494 -313.45505 180)
		(property "Reference" "R536"
			(at 0 0 0)
			(layer "B.SilkS")
			(hide yes)
			(effects
				(font
					(size 1.27 1.27)
				)
				(justify mirror)
			)
		)
		(property "Value" ""
			(at 0 0 0)
			(layer "B.Fab")
			(effects
				(font
					(size 1.27 1.27)
				)
				(justify mirror)
			)
		)
		(duplicate_pad_numbers_are_jumpers no)
		(fp_line
			(start 0.7874 0.4064)
			(end 0.7874 -0.4064)
			(stroke
				(width 0.1524)
				(type default)
			)
			(layer "B.SilkS")
		)
		(fp_line
			(start 0.7874 -0.4064)
			(end -0.7874 -0.4064)
			(stroke
				(width 0.1524)
				(type default)
			)
			(layer "B.SilkS")
		)
		(fp_line
			(start -0.7874 0.4064)
			(end 0.7874 0.4064)
			(stroke
				(width 0.1524)
				(type default)
			)
			(layer "B.SilkS")
		)
		(fp_line
			(start -0.7874 -0.4064)
			(end -0.7874 0.4064)
			(stroke
				(width 0.1524)
				(type default)
			)
			(layer "B.SilkS")
		)
		(fp_line
			(start 0.67945 0.3048)
			(end 0.67945 -0.305054)
			(stroke
				(width 0.1)
				(type default)
			)
			(layer "B.Fab")
		)
		(fp_line
			(start 0.67945 -0.305054)
			(end 0.12065 -0.305054)
			(stroke
				(width 0.1)
				(type default)
			)
			(layer "B.Fab")
		)
		(fp_line
			(start 0.12065 0.3048)
			(end 0.67945 0.3048)
			(stroke
				(width 0.1)
				(type default)
			)
			(layer "B.Fab")
		)
		(fp_line
			(start 0.12065 0.2794)
			(end 0.12065 0.3048)
			(stroke
				(width 0.1)
				(type default)
			)
			(layer "B.Fab")
		)
		(fp_line
			(start 0.12065 -0.2794)
			(end -0.12065 -0.2794)
			(stroke
				(width 0.1)
				(type default)
			)
			(layer "B.Fab")
		)
		(fp_line
			(start 0.12065 -0.305054)
			(end 0.12065 -0.2794)
			(stroke
				(width 0.1)
				(type default)
			)
			(layer "B.Fab")
		)
		(fp_line
			(start -0.120396 0.3048)
			(end -0.120396 0.2794)
			(stroke
				(width 0.1)
				(type default)
			)
			(layer "B.Fab")
		)
		(fp_line
			(start -0.120396 0.2794)
			(end 0.12065 0.2794)
			(stroke
				(width 0.1)
				(type default)
			)
			(layer "B.Fab")
		)
		(fp_line
			(start -0.12065 -0.2794)
			(end -0.12065 -0.3048)
			(stroke
				(width 0.1)
				(type default)
			)
			(layer "B.Fab")
		)
		(fp_line
			(start -0.12065 -0.3048)
			(end -0.67945 -0.3048)
			(stroke
				(width 0.1)
				(type default)
			)
			(layer "B.Fab")
		)
		(fp_line
			(start -0.67945 0.3048)
			(end -0.120396 0.3048)
			(stroke
				(width 0.1)
				(type default)
			)
			(layer "B.Fab")
		)
		(fp_line
			(start -0.67945 -0.3048)
			(end -0.67945 0.3048)
			(stroke
				(width 0.1)
				(type default)
			)
			(layer "B.Fab")
		)
		(pad "1" smd circle
			(at 0.40005 0)
			(size 0 0)
			(layers "B.Cu" "B.Mask" "B.Paste")
			(net "CPU1_THERMTRIP_N")
		)
		(pad "2" smd circle
			(at -0.40005 0)
			(size 0 0)
			(layers "B.Cu" "B.Mask" "B.Paste")
			(net "PVDD18_S5_P1")
		)
	)
)
